# T6G (Grand Teton) — schematic netlist excerpt (pin names and nets, part order shuffled) for the footprints in the layout excerpt that follows; sources: Cadence DE-HDL packaged netlist, KiCad conversion of 04192023_DAF0TMB3IC0_F0TG_MB_C_brd_V02_OCP.brd

R3105  Q_RES  0 5% CHIP  pkg 0402LF  page 248 : A = SMB_BMC_SWB_SCL ; B = SMB_BMC_SWB_R_SCL
PC2260  Q_CAP  22UF 16V 20% X6S  pkg C0805  page 190 : A = SW_P3V3_AUX_FLT ; B = GND
PC166  Q_CAP  560PF 50V 10% EMPTY  pkg C0402  page 206 : A = SW_PVDDIO_P0_SW3 ; B = SW_PVDDIO_P0_SW3_RC

(kicad_pcb
	(version 20260206)
	(generator "pcbnew")
	(generator_version "10.0")
	(general
		(thickness 1.6)
		(legacy_teardrops no)
	)
	(paper "A4")
	(title_block
		(title "04192023_DAF0TMB3IC0_F0TG_MB_C_brd_V02_OCP.brd")
		(comment 1 "Grand Teton / footprints 1621-1623 of 8354")
	)
	(layers
		(0 "F.Cu" signal "TOP")
		(4 "In1.Cu" signal "GND")
		(6 "In2.Cu" signal "IN1")
		(8 "In3.Cu" signal "GND1")
		(10 "In4.Cu" signal "IN2")
		(12 "In5.Cu" signal "GND2")
		(14 "In6.Cu" signal "IN3")
		(16 "In7.Cu" signal "GND3")
		(18 "In8.Cu" signal "VCC")
		(20 "In9.Cu" signal "VCC1")
		(22 "In10.Cu" signal "GND4")
		(24 "In11.Cu" signal "IN4")
		(26 "In12.Cu" signal "GND5")
		(28 "In13.Cu" signal "IN5")
		(30 "In14.Cu" signal "GND6")
		(32 "In15.Cu" signal "IN6")
		(34 "In16.Cu" signal "GND7")
		(2 "B.Cu" signal "BOTTOM")
		(9 "F.Adhes" user "F.Adhesive")
		(11 "B.Adhes" user "B.Adhesive")
		(13 "F.Paste" user "Package Geometry/Pastemask Top")
		(15 "B.Paste" user "Package Geometry/Pastemask Bottom")
		(5 "F.SilkS" user "Ref Des/Silkscreen Top")
		(7 "B.SilkS" user "Ref Des/Silkscreen Bottom")
		(1 "F.Mask" user "Board Geometry/Soldermask Top")
		(3 "B.Mask" user "Board Geometry/Soldermask Bottom")
		(17 "Dwgs.User" user "User.Drawings")
		(19 "Cmts.User" user "User.Comments")
		(21 "Eco1.User" user "User.Eco1")
		(23 "Eco2.User" user "User.Eco2")
		(25 "Edge.Cuts" user "Board Geometry/Outline")
		(27 "Margin" user)
		(31 "F.CrtYd" user "Package Geometry/Place Bound Top")
		(29 "B.CrtYd" user "Package Geometry/Place Bound Bottom")
		(35 "F.Fab" user "Ref Des/Assembly Top")
		(33 "B.Fab" user "Ref Des/Assembly Bottom")
	)
	(footprint ""
		(layer "F.Cu")
		(at 280.008584 -343.712038 180)
		(property "Reference" "PC166"
			(at 0 0 180)
			(layer "F.SilkS")
			(hide yes)
			(effects
				(font
					(size 1.27 1.27)
				)
			)
		)
		(property "Value" ""
			(at 0 0 180)
			(layer "F.Fab")
			(effects
				(font
					(size 1.27 1.27)
				)
			)
		)
		(duplicate_pad_numbers_are_jumpers no)
		(fp_line
			(start 0.7874 0.4064)
			(end -0.7874 0.4064)
			(stroke
				(width 0.1524)
				(type default)
			)
			(layer "F.SilkS")
		)
		(fp_line
			(start 0.7874 -0.4064)
			(end 0.7874 0.4064)
			(stroke
				(width 0.1524)
				(type default)
			)
			(layer "F.SilkS")
		)
		(fp_line
			(start -0.7874 0.4064)
			(end -0.7874 -0.4064)
			(stroke
				(width 0.1524)
				(type default)
			)
			(layer "F.SilkS")
		)
		(fp_line
			(start -0.7874 -0.4064)
			(end 0.7874 -0.4064)
			(stroke
				(width 0.1524)
				(type default)
			)
			(layer "F.SilkS")
		)
		(fp_line
			(start 0.67945 0.3048)
			(end 0.120396 0.3048)
			(stroke
				(width 0.1)
				(type default)
			)
			(layer "F.Fab")
		)
		(fp_line
			(start 0.67945 -0.3048)
			(end 0.67945 0.3048)
			(stroke
				(width 0.1)
				(type default)
			)
			(layer "F.Fab")
		)
		(fp_line
			(start 0.12065 -0.2794)
			(end 0.12065 -0.3048)
			(stroke
				(width 0.1)
				(type default)
			)
			(layer "F.Fab")
		)
		(fp_line
			(start 0.12065 -0.3048)
			(end 0.67945 -0.3048)
			(stroke
				(width 0.1)
				(type default)
			)
			(layer "F.Fab")
		)
		(fp_line
			(start 0.120396 0.3048)
			(end 0.120396 0.2794)
			(stroke
				(width 0.1)
				(type default)
			)
			(layer "F.Fab")
		)
		(fp_line
			(start 0.120396 0.2794)
			(end -0.12065 0.2794)
			(stroke
				(width 0.1)
				(type default)
			)
			(layer "F.Fab")
		)
		(fp_line
			(start -0.12065 0.3048)
			(end -0.67945 0.3048)
			(stroke
				(width 0.1)
				(type default)
			)
			(layer "F.Fab")
		)
		(fp_line
			(start -0.12065 0.2794)
			(end -0.12065 0.3048)
			(stroke
				(width 0.1)
				(type default)
			)
			(layer "F.Fab")
		)
		(fp_line
			(start -0.12065 -0.2794)
			(end 0.12065 -0.2794)
			(stroke
				(width 0.1)
				(type default)
			)
			(layer "F.Fab")
		)
		(fp_line
			(start -0.12065 -0.305054)
			(end -0.12065 -0.2794)
			(stroke
				(width 0.1)
				(type default)
			)
			(layer "F.Fab")
		)
		(fp_line
			(start -0.67945 0.3048)
			(end -0.67945 -0.305054)
			(stroke
				(width 0.1)
				(type default)
			)
			(layer "F.Fab")
		)
		(fp_line
			(start -0.67945 -0.305054)
			(end -0.12065 -0.305054)
			(stroke
				(width 0.1)
				(type default)
			)
			(layer "F.Fab")
		)
		(pad "1" smd circle
			(at -0.40005 0 180)
			(size 0 0)
			(layers "F.Cu" "F.Mask" "F.Paste")
			(net "SW_PVDDIO_P0_SW3")
		)
		(pad "2" smd circle
			(at 0.40005 0 180)
			(size 0 0)
			(layers "F.Cu" "F.Mask" "F.Paste")
			(net "SW_PVDDIO_P0_SW3_RC")
		)
	)
	(footprint ""
		(layer "F.Cu")
		(at 446.493392 -47.506382 -90)
		(property "Reference" "PC2260"
			(at 0 0 270)
			(layer "F.SilkS")
			(hide yes)
			(effects
				(font
					(size 1.27 1.27)
				)
			)
		)
		(property "Value" ""
			(at 0 0 270)
			(layer "F.Fab")
			(effects
				(font
					(size 1.27 1.27)
				)
			)
		)
		(duplicate_pad_numbers_are_jumpers no)
		(fp_line
			(start -1.524 0.762)
			(end -1.524 -0.762)
			(stroke
				(width 0.1524)
				(type default)
			)
			(layer "F.SilkS")
		)
		(fp_line
			(start 1.524 0.762)
			(end -1.524 0.762)
			(stroke
				(width 0.1524)
				(type default)
			)
			(layer "F.SilkS")
		)
		(fp_line
			(start -1.524 -0.762)
			(end 1.524 -0.762)
			(stroke
				(width 0.1524)
				(type default)
			)
			(layer "F.SilkS")
		)
		(fp_line
			(start 1.524 -0.762)
			(end 1.524 0.762)
			(stroke
				(width 0.1524)
				(type default)
			)
			(layer "F.SilkS")
		)
		(fp_line
			(start -1.1049 0.724916)
			(end 1.1049 0.724916)
			(stroke
				(width 0.1)
				(type default)
			)
			(layer "F.Fab")
		)
		(fp_line
			(start 1.1049 0.724916)
			(end 1.1049 -0.724916)
			(stroke
				(width 0.1)
				(type default)
			)
			(layer "F.Fab")
		)
		(fp_line
			(start -1.1049 -0.724916)
			(end -1.1049 0.724916)
			(stroke
				(width 0.1)
				(type default)
			)
			(layer "F.Fab")
		)
		(fp_line
			(start 1.1049 -0.724916)
			(end -1.1049 -0.724916)
			(stroke
				(width 0.1)
				(type default)
			)
			(layer "F.Fab")
		)
		(pad "1" smd rect
			(at -0.889 0 90)
			(size 1.016 1.27)
			(layers "F.Cu" "F.Mask" "F.Paste")
			(net "SW_P3V3_AUX_FLT")
		)
		(pad "2" smd rect
			(at 0.889 0 90)
			(size 1.016 1.27)
			(layers "F.Cu" "F.Mask" "F.Paste")
			(net "GND")
		)
	)
	(footprint ""
		(layer "F.Cu")
		(at 166.1668 -428.5996 180)
		(property "Reference" "R3105"
			(at 0 0 180)
			(layer "F.SilkS")
			(hide yes)
			(effects
				(font
					(size 1.27 1.27)
				)
			)
		)
		(property "Value" ""
			(at 0 0 180)
			(layer "F.Fab")
			(effects
				(font
					(size 1.27 1.27)
				)
			)
		)
		(duplicate_pad_numbers_are_jumpers no)
		(fp_line
			(start 0.7874 0.4064)
			(end -0.7874 0.4064)
			(stroke
				(width 0.1524)
				(type default)
			)
			(layer "F.SilkS")
		)
		(fp_line
			(start 0.7874 -0.4064)
			(end 0.7874 0.4064)
			(stroke
				(width 0.1524)
				(type default)
			)
			(layer "F.SilkS")
		)
		(fp_line
			(start -0.7874 0.4064)
			(end -0.7874 -0.4064)
			(stroke
				(width 0.1524)
				(type default)
			)
			(layer "F.SilkS")
		)
		(fp_line
			(start -0.7874 -0.4064)
			(end 0.7874 -0.4064)
			(stroke
				(width 0.1524)
				(type default)
			)
			(layer "F.SilkS")
		)
		(fp_line
			(start 0.67945 0.3048)
			(end 0.120396 0.3048)
			(stroke
				(width 0.1)
				(type default)
			)
			(layer "F.Fab")
		)
		(fp_line
			(start 0.67945 -0.3048)
			(end 0.67945 0.3048)
			(stroke
				(width 0.1)
				(type default)
			)
			(layer "F.Fab")
		)
		(fp_line
			(start 0.12065 -0.2794)
			(end 0.12065 -0.3048)
			(stroke
				(width 0.1)
				(type default)
			)
			(layer "F.Fab")
		)
		(fp_line
			(start 0.12065 -0.3048)
			(end 0.67945 -0.3048)
			(stroke
				(width 0.1)
				(type default)
			)
			(layer "F.Fab")
		)
		(fp_line
			(start 0.120396 0.3048)
			(end 0.120396 0.2794)
			(stroke
				(width 0.1)
				(type default)
			)
			(layer "F.Fab")
		)
		(fp_line
			(start 0.120396 0.2794)
			(end -0.12065 0.2794)
			(stroke
				(width 0.1)
				(type default)
			)
			(layer "F.Fab")
		)
		(fp_line
			(start -0.12065 0.3048)
			(end -0.67945 0.3048)
			(stroke
				(width 0.1)
				(type default)
			)
			(layer "F.Fab")
		)
		(fp_line
			(start -0.12065 0.2794)
			(end -0.12065 0.3048)
			(stroke
				(width 0.1)
				(type default)
			)
			(layer "F.Fab")
		)
		(fp_line
			(start -0.12065 -0.2794)
			(end 0.12065 -0.2794)
			(stroke
				(width 0.1)
				(type default)
			)
			(layer "F.Fab")
		)
		(fp_line
			(start -0.12065 -0.305054)
			(end -0.12065 -0.2794)
			(stroke
				(width 0.1)
				(type default)
			)
			(layer "F.Fab")
		)
		(fp_line
			(start -0.67945 0.3048)
			(end -0.67945 -0.305054)
			(stroke
				(width 0.1)
				(type default)
			)
			(layer "F.Fab")
		)
		(fp_line
			(start -0.67945 -0.305054)
			(end -0.12065 -0.305054)
			(stroke
				(width 0.1)
				(type default)
			)
			(layer "F.Fab")
		)
		(pad "1" smd circle
			(at -0.40005 0 180)
			(size 0 0)
			(layers "F.Cu" "F.Mask" "F.Paste")
			(net "SMB_BMC_SWB_SCL")
		)
		(pad "2" smd circle
			(at 0.40005 0 180)
			(size 0 0)
			(layers "F.Cu" "F.Mask" "F.Paste")
			(net "SMB_BMC_SWB_R_SCL")
		)
	)
)
